(kicad_pcb
	(version 20260206)
	(generator "pcbnew")
	(generator_version "10.0")
	(general
		(thickness 1.6)
		(legacy_teardrops no)
	)
	(paper "A4")
	(title_block
		(title "dpb — 14545-sa.0730WZS0815.brd")
		(comment 1 "Honey Badger (Wiwynn) / footprints 718-725 of 1066")
	)
	(layers
		(0 "F.Cu" signal "TOP")
		(4 "In1.Cu" signal "L2GND")
		(6 "In2.Cu" signal "L3")
		(8 "In3.Cu" signal "L4VCC")
		(10 "In4.Cu" signal "L5VCC")
		(12 "In5.Cu" signal "L6")
		(14 "In6.Cu" signal "L7GND")
		(2 "B.Cu" signal "BOTTOM")
		(9 "F.Adhes" user "F.Adhesive")
		(11 "B.Adhes" user "B.Adhesive")
		(13 "F.Paste" user "Package Geometry/Pastemask Top")
		(15 "B.Paste" user "Package Geometry/Pastemask Bottom")
		(5 "F.SilkS" user "Ref Des/Silkscreen Top")
		(7 "B.SilkS" user "Ref Des/Silkscreen Bottom")
		(1 "F.Mask" user "Board Geometry/Soldermask Top")
		(3 "B.Mask" user "Board Geometry/Soldermask Bottom")
		(17 "Dwgs.User" user "User.Drawings")
		(19 "Cmts.User" user "User.Comments")
		(21 "Eco1.User" user "User.Eco1")
		(23 "Eco2.User" user "User.Eco2")
		(25 "Edge.Cuts" user "Board Geometry/Outline")
		(27 "Margin" user)
		(31 "F.CrtYd" user "Package Geometry/Place Bound Top")
		(29 "B.CrtYd" user "Package Geometry/Place Bound Bottom")
		(35 "F.Fab" user "Ref Des/Assembly Top")
		(33 "B.Fab" user "Ref Des/Assembly Bottom")
	)
	(footprint ""
		(layer "F.Cu")
		(at 14.604746 -53.7337 -90)
		(property "Reference" "R300"
			(at 0 0 270)
			(layer "F.SilkS")
			(hide yes)
			(effects
				(font
					(size 1.27 1.27)
				)
			)
		)
		(property "Value" "0R2J-2-GP"
			(at 0.064008 -3.993896 270)
			(unlocked yes)
			(layer "F.Fab")
			(hide yes)
			(effects
				(font
					(size 1.016 1.016)
					(thickness 0.1524)
				)
			)
		)
		(property "Device Type" "R402H16"
			(at 0.064008 -5.517896 270)
			(unlocked yes)
			(layer "F.Fab")
			(hide yes)
			(effects
				(font
					(size 1.016 1.016)
					(thickness 0.1524)
				)
			)
		)
		(duplicate_pad_numbers_are_jumpers no)
		(fp_line
			(start -0.508 -0.9398)
			(end -0.508 0.9398)
			(stroke
				(width 0.1524)
				(type default)
			)
			(layer "F.SilkS")
		)
		(fp_line
			(start 0.508 -0.9398)
			(end -0.508 -0.9398)
			(stroke
				(width 0.1524)
				(type default)
			)
			(layer "F.SilkS")
		)
		(fp_rect
			(start -0.508 0.9398)
			(end 0.508 -0.9398)
			(stroke
				(width 0)
				(type default)
			)
			(fill no)
			(layer "F.CrtYd")
		)
		(fp_rect
			(start -0.508 0.9398)
			(end 0.508 -0.9398)
			(stroke
				(width 0)
				(type default)
			)
			(fill no)
			(layer "F.Fab")
		)
		(pad "1" smd custom
			(at 0 -0.4445 270)
			(size 0.1397 0.1397)
			(layers "F.Cu" "F.Mask" "F.Paste")
			(net "FLT_NET_HDD14")
			(options
				(clearance outline)
				(anchor circle)
			)
			(primitives
				(gr_poly
					(pts
						(arc
							(start -0.1778 -0.2794)
							(mid -0.249642 -0.249642)
							(end -0.2794 -0.1778)
						)
						(arc
							(start -0.2794 0.1778)
							(mid -0.249642 0.249642)
							(end -0.1778 0.2794)
						)
						(arc
							(start 0.1778 0.2794)
							(mid 0.249642 0.249642)
							(end 0.2794 0.1778)
						)
						(arc
							(start 0.2794 -0.1778)
							(mid 0.249642 -0.249642)
							(end 0.1778 -0.2794)
						)
					)
					(width 0)
					(fill yes)
				)
			)
		)
		(pad "2" smd custom
			(at 0 0.4445 270)
			(size 0.1397 0.1397)
			(layers "F.Cu" "F.Mask" "F.Paste")
			(net "FLT_HDD14_DRIVE")
			(options
				(clearance outline)
				(anchor circle)
			)
			(primitives
				(gr_poly
					(pts
						(arc
							(start -0.1778 -0.2794)
							(mid -0.249642 -0.249642)
							(end -0.2794 -0.1778)
						)
						(arc
							(start -0.2794 0.1778)
							(mid -0.249642 0.249642)
							(end -0.1778 0.2794)
						)
						(arc
							(start 0.1778 0.2794)
							(mid 0.249642 0.249642)
							(end 0.2794 0.1778)
						)
						(arc
							(start 0.2794 -0.1778)
							(mid 0.249642 -0.249642)
							(end 0.1778 -0.2794)
						)
					)
					(width 0)
					(fill yes)
				)
			)
		)
	)
	(footprint ""
		(layer "F.Cu")
		(at 252.499622 -170.999912)
		(property "Reference" "H15"
			(at 0 0 0)
			(layer "F.SilkS")
			(hide yes)
			(effects
				(font
					(size 1.27 1.27)
				)
			)
		)
		(property "Value" "HOLE315R140"
			(at 0 -7.5692 0)
			(unlocked yes)
			(layer "F.Fab")
			(hide yes)
			(effects
				(font
					(size 1.016 1.016)
					(thickness 0.1524)
				)
			)
		)
		(property "Device Type" "HOLE315R140"
			(at 0 -9.0932 0)
			(unlocked yes)
			(layer "F.Fab")
			(hide yes)
			(effects
				(font
					(size 1.016 1.016)
					(thickness 0.1524)
				)
			)
		)
		(duplicate_pad_numbers_are_jumpers no)
		(fp_poly
			(pts
				(arc
					(start 4.3053 0)
					(mid -4.3053 0)
					(end 4.3053 0)
				)
			)
			(stroke
				(width 0)
				(type default)
			)
			(fill no)
			(layer "F.CrtYd")
		)
		(fp_poly
			(pts
				(arc
					(start 4.3053 0)
					(mid -4.3053 0)
					(end 4.3053 0)
				)
			)
			(stroke
				(width 0)
				(type default)
			)
			(fill no)
			(layer "F.Fab")
		)
		(pad "1" thru_hole circle
			(at 0.00127 0.00127)
			(size 8.001 8.001)
			(drill 3.556)
			(layers "*.Cu" "*.Mask")
			(remove_unused_layers no)
			(net "GND")
			(clearance -1.7145)
			(thermal_gap 0.3048)
			(padstack
				(mode front_inner_back)
				(layer "Inner"
					(shape circle)
					(size 3.9624 3.9624)
					(clearance 0.3048)
				)
				(layer "B.Cu"
					(shape circle)
					(size 8.001 8.001)
					(clearance -1.7145)
				)
			)
		)
	)
	(footprint ""
		(layer "F.Cu")
		(at 8.5852 -151.7396 90)
		(property "Reference" "R547"
			(at 0 0 90)
			(layer "F.SilkS")
			(hide yes)
			(effects
				(font
					(size 1.27 1.27)
				)
			)
		)
		(property "Value" "0R2J-2-GP"
			(at 0.064008 -3.993896 90)
			(unlocked yes)
			(layer "F.Fab")
			(hide yes)
			(effects
				(font
					(size 1.016 1.016)
					(thickness 0.1524)
				)
			)
		)
		(property "Device Type" "R402H16"
			(at 0.064008 -5.517896 90)
			(unlocked yes)
			(layer "F.Fab")
			(hide yes)
			(effects
				(font
					(size 1.016 1.016)
					(thickness 0.1524)
				)
			)
		)
		(duplicate_pad_numbers_are_jumpers no)
		(fp_line
			(start 0.508 -0.9398)
			(end -0.508 -0.9398)
			(stroke
				(width 0.1524)
				(type default)
			)
			(layer "F.SilkS")
		)
		(fp_line
			(start -0.508 -0.9398)
			(end -0.508 0.9398)
			(stroke
				(width 0.1524)
				(type default)
			)
			(layer "F.SilkS")
		)
		(fp_rect
			(start -0.508 0.9398)
			(end 0.508 -0.9398)
			(stroke
				(width 0)
				(type default)
			)
			(fill no)
			(layer "F.CrtYd")
		)
		(fp_rect
			(start -0.508 0.9398)
			(end 0.508 -0.9398)
			(stroke
				(width 0)
				(type default)
			)
			(fill no)
			(layer "F.Fab")
		)
		(pad "1" smd custom
			(at 0 -0.4445 90)
			(size 0.1397 0.1397)
			(layers "F.Cu" "F.Mask" "F.Paste")
			(net "I2C_C_SDA_DAMP_B")
			(options
				(clearance outline)
				(anchor circle)
			)
			(primitives
				(gr_poly
					(pts
						(arc
							(start -0.1778 -0.2794)
							(mid -0.249642 -0.249642)
							(end -0.2794 -0.1778)
						)
						(arc
							(start -0.2794 0.1778)
							(mid -0.249642 0.249642)
							(end -0.1778 0.2794)
						)
						(arc
							(start 0.1778 0.2794)
							(mid 0.249642 0.249642)
							(end 0.2794 0.1778)
						)
						(arc
							(start 0.2794 -0.1778)
							(mid 0.249642 -0.249642)
							(end 0.1778 -0.2794)
						)
					)
					(width 0)
					(fill yes)
				)
			)
		)
		(pad "2" smd custom
			(at 0 0.4445 90)
			(size 0.1397 0.1397)
			(layers "F.Cu" "F.Mask" "F.Paste")
			(net "I2C_C_SDA")
			(options
				(clearance outline)
				(anchor circle)
			)
			(primitives
				(gr_poly
					(pts
						(arc
							(start -0.1778 -0.2794)
							(mid -0.249642 -0.249642)
							(end -0.2794 -0.1778)
						)
						(arc
							(start -0.2794 0.1778)
							(mid -0.249642 0.249642)
							(end -0.1778 0.2794)
						)
						(arc
							(start 0.1778 0.2794)
							(mid 0.249642 0.249642)
							(end 0.2794 0.1778)
						)
						(arc
							(start 0.2794 -0.1778)
							(mid 0.249642 -0.249642)
							(end 0.1778 -0.2794)
						)
					)
					(width 0)
					(fill yes)
				)
			)
		)
	)
	(footprint ""
		(layer "F.Cu")
		(at 78.994 -94.488 180)
		(property "Reference" "C388"
			(at 0 0 180)
			(layer "F.SilkS")
			(hide yes)
			(effects
				(font
					(size 1.27 1.27)
				)
			)
		)
		(property "Value" "SCD033U25V2KX-GP"
			(at 1.1811 -2.7051 180)
			(unlocked yes)
			(layer "F.Fab")
			(hide yes)
			(effects
				(font
					(size 1.016 1.016)
					(thickness 0.1524)
				)
			)
		)
		(property "Device Type" "C402H22"
			(at 1.1811 -4.2291 180)
			(unlocked yes)
			(layer "F.Fab")
			(hide yes)
			(effects
				(font
					(size 1.016 1.016)
					(thickness 0.1524)
				)
			)
		)
		(duplicate_pad_numbers_are_jumpers no)
		(fp_rect
			(start -0.4318 0.9525)
			(end 0.4318 -0.9525)
			(stroke
				(width 0)
				(type default)
			)
			(fill no)
			(layer "F.CrtYd")
		)
		(fp_rect
			(start -0.4318 0.9525)
			(end 0.4318 -0.9525)
			(stroke
				(width 0)
				(type default)
			)
			(fill no)
			(layer "F.Fab")
		)
		(pad "1" smd custom
			(at 0 -0.4445 180)
			(size 0.1524 0.1524)
			(layers "F.Cu" "F.Mask" "F.Paste")
			(net "P12V")
			(options
				(clearance outline)
				(anchor circle)
			)
			(primitives
				(gr_poly
					(pts
						(arc
							(start 0.3048 -0.2032)
							(mid 0.275042 -0.275042)
							(end 0.2032 -0.3048)
						)
						(arc
							(start -0.2032 -0.3048)
							(mid -0.275042 -0.275042)
							(end -0.3048 -0.2032)
						)
						(arc
							(start -0.3048 0.2032)
							(mid -0.275042 0.275042)
							(end -0.2032 0.3048)
						)
						(arc
							(start 0.2032 0.3048)
							(mid 0.275042 0.275042)
							(end 0.3048 0.2032)
						)
					)
					(width 0)
					(fill yes)
				)
			)
		)
		(pad "2" smd custom
			(at 0 0.4445 180)
			(size 0.1524 0.1524)
			(layers "F.Cu" "F.Mask" "F.Paste")
			(net "SW_HDD9_N")
			(options
				(clearance outline)
				(anchor circle)
			)
			(primitives
				(gr_poly
					(pts
						(arc
							(start 0.3048 -0.2032)
							(mid 0.275042 -0.275042)
							(end 0.2032 -0.3048)
						)
						(arc
							(start -0.2032 -0.3048)
							(mid -0.275042 -0.275042)
							(end -0.3048 -0.2032)
						)
						(arc
							(start -0.3048 0.2032)
							(mid -0.275042 0.275042)
							(end -0.2032 0.3048)
						)
						(arc
							(start 0.2032 0.3048)
							(mid 0.275042 0.275042)
							(end 0.3048 0.2032)
						)
					)
					(width 0)
					(fill yes)
				)
			)
		)
	)
	(footprint ""
		(layer "F.Cu")
		(at 79.211932 -496.145312 90)
		(property "Reference" "R182"
			(at 0 0 90)
			(layer "F.SilkS")
			(hide yes)
			(effects
				(font
					(size 1.27 1.27)
				)
			)
		)
		(property "Value" "0R2J-2-GP"
			(at 0.064008 -3.993896 90)
			(unlocked yes)
			(layer "F.Fab")
			(hide yes)
			(effects
				(font
					(size 1.016 1.016)
					(thickness 0.1524)
				)
			)
		)
		(property "Device Type" "R402H16"
			(at 0.064008 -5.517896 90)
			(unlocked yes)
			(layer "F.Fab")
			(hide yes)
			(effects
				(font
					(size 1.016 1.016)
					(thickness 0.1524)
				)
			)
		)
		(duplicate_pad_numbers_are_jumpers no)
		(fp_line
			(start 0.508 -0.9398)
			(end -0.508 -0.9398)
			(stroke
				(width 0.1524)
				(type default)
			)
			(layer "F.SilkS")
		)
		(fp_line
			(start -0.508 -0.9398)
			(end -0.508 0.9398)
			(stroke
				(width 0.1524)
				(type default)
			)
			(layer "F.SilkS")
		)
		(fp_rect
			(start -0.508 0.9398)
			(end 0.508 -0.9398)
			(stroke
				(width 0)
				(type default)
			)
			(fill no)
			(layer "F.CrtYd")
		)
		(fp_rect
			(start -0.508 0.9398)
			(end 0.508 -0.9398)
			(stroke
				(width 0)
				(type default)
			)
			(fill no)
			(layer "F.Fab")
		)
		(pad "1" smd custom
			(at 0 -0.4445 90)
			(size 0.1397 0.1397)
			(layers "F.Cu" "F.Mask" "F.Paste")
			(net "SW_PWR_HDD5")
			(options
				(clearance outline)
				(anchor circle)
			)
			(primitives
				(gr_poly
					(pts
						(arc
							(start -0.1778 -0.2794)
							(mid -0.249642 -0.249642)
							(end -0.2794 -0.1778)
						)
						(arc
							(start -0.2794 0.1778)
							(mid -0.249642 0.249642)
							(end -0.1778 0.2794)
						)
						(arc
							(start 0.1778 0.2794)
							(mid 0.249642 0.249642)
							(end 0.2794 0.1778)
						)
						(arc
							(start 0.2794 -0.1778)
							(mid 0.249642 -0.249642)
							(end 0.1778 -0.2794)
						)
					)
					(width 0)
					(fill yes)
				)
			)
		)
		(pad "2" smd custom
			(at 0 0.4445 90)
			(size 0.1397 0.1397)
			(layers "F.Cu" "F.Mask" "F.Paste")
			(net "SW_PWR_R_HDD5")
			(options
				(clearance outline)
				(anchor circle)
			)
			(primitives
				(gr_poly
					(pts
						(arc
							(start -0.1778 -0.2794)
							(mid -0.249642 -0.249642)
							(end -0.2794 -0.1778)
						)
						(arc
							(start -0.2794 0.1778)
							(mid -0.249642 0.249642)
							(end -0.1778 0.2794)
						)
						(arc
							(start 0.1778 0.2794)
							(mid 0.249642 0.249642)
							(end 0.2794 0.1778)
						)
						(arc
							(start 0.2794 -0.1778)
							(mid 0.249642 -0.249642)
							(end 0.1778 -0.2794)
						)
					)
					(width 0)
					(fill yes)
				)
			)
		)
	)
	(footprint ""
		(layer "F.Cu")
		(at 177.685446 -460.536036 90)
		(property "Reference" "C363"
			(at 0 0 90)
			(layer "F.SilkS")
			(hide yes)
			(effects
				(font
					(size 1.27 1.27)
				)
			)
		)
		(property "Value" "SC1U10V2KX-1GP"
			(at 1.1811 -2.7051 90)
			(unlocked yes)
			(layer "F.Fab")
			(hide yes)
			(effects
				(font
					(size 1.016 1.016)
					(thickness 0.1524)
				)
			)
		)
		(property "Device Type" "C402H22"
			(at 1.1811 -4.2291 90)
			(unlocked yes)
			(layer "F.Fab")
			(hide yes)
			(effects
				(font
					(size 1.016 1.016)
					(thickness 0.1524)
				)
			)
		)
		(duplicate_pad_numbers_are_jumpers no)
		(fp_rect
			(start -0.4318 0.9525)
			(end 0.4318 -0.9525)
			(stroke
				(width 0)
				(type default)
			)
			(fill no)
			(layer "F.CrtYd")
		)
		(fp_rect
			(start -0.4318 0.9525)
			(end 0.4318 -0.9525)
			(stroke
				(width 0)
				(type default)
			)
			(fill no)
			(layer "F.Fab")
		)
		(pad "1" smd custom
			(at 0 -0.4445 90)
			(size 0.1524 0.1524)
			(layers "F.Cu" "F.Mask" "F.Paste")
			(net "P3V3")
			(options
				(clearance outline)
				(anchor circle)
			)
			(primitives
				(gr_poly
					(pts
						(arc
							(start 0.3048 -0.2032)
							(mid 0.275042 -0.275042)
							(end 0.2032 -0.3048)
						)
						(arc
							(start -0.2032 -0.3048)
							(mid -0.275042 -0.275042)
							(end -0.3048 -0.2032)
						)
						(arc
							(start -0.3048 0.2032)
							(mid -0.275042 0.275042)
							(end -0.2032 0.3048)
						)
						(arc
							(start 0.2032 0.3048)
							(mid 0.275042 0.275042)
							(end 0.3048 0.2032)
						)
					)
					(width 0)
					(fill yes)
				)
			)
		)
		(pad "2" smd custom
			(at 0 0.4445 90)
			(size 0.1524 0.1524)
			(layers "F.Cu" "F.Mask" "F.Paste")
			(net "GND")
			(options
				(clearance outline)
				(anchor circle)
			)
			(primitives
				(gr_poly
					(pts
						(arc
							(start 0.3048 -0.2032)
							(mid 0.275042 -0.275042)
							(end 0.2032 -0.3048)
						)
						(arc
							(start -0.2032 -0.3048)
							(mid -0.275042 -0.275042)
							(end -0.3048 -0.2032)
						)
						(arc
							(start -0.3048 0.2032)
							(mid -0.275042 0.275042)
							(end -0.2032 0.3048)
						)
						(arc
							(start 0.2032 0.3048)
							(mid 0.275042 0.275042)
							(end 0.3048 0.2032)
						)
					)
					(width 0)
					(fill yes)
				)
			)
		)
	)
	(footprint ""
		(layer "F.Cu")
		(at 58.927746 -25.6667 90)
		(property "Reference" "PR18"
			(at 0 0 90)
			(layer "F.SilkS")
			(hide yes)
			(effects
				(font
					(size 1.27 1.27)
				)
			)
		)
		(property "Value" "0R2J-2-GP"
			(at 0.064008 -3.993896 90)
			(unlocked yes)
			(layer "F.Fab")
			(hide yes)
			(effects
				(font
					(size 1.016 1.016)
					(thickness 0.1524)
				)
			)
		)
		(property "Device Type" "R402H16"
			(at 0.064008 -5.517896 90)
			(unlocked yes)
			(layer "F.Fab")
			(hide yes)
			(effects
				(font
					(size 1.016 1.016)
					(thickness 0.1524)
				)
			)
		)
		(duplicate_pad_numbers_are_jumpers no)
		(fp_line
			(start 0.508 -0.9398)
			(end -0.508 -0.9398)
			(stroke
				(width 0.1524)
				(type default)
			)
			(layer "F.SilkS")
		)
		(fp_line
			(start -0.508 -0.9398)
			(end -0.508 0.9398)
			(stroke
				(width 0.1524)
				(type default)
			)
			(layer "F.SilkS")
		)
		(fp_rect
			(start -0.508 0.9398)
			(end 0.508 -0.9398)
			(stroke
				(width 0)
				(type default)
			)
			(fill no)
			(layer "F.CrtYd")
		)
		(fp_rect
			(start -0.508 0.9398)
			(end 0.508 -0.9398)
			(stroke
				(width 0)
				(type default)
			)
			(fill no)
			(layer "F.Fab")
		)
		(pad "1" smd custom
			(at 0 -0.4445 90)
			(size 0.1397 0.1397)
			(layers "F.Cu" "F.Mask" "F.Paste")
			(net "P5VB_RF")
			(options
				(clearance outline)
				(anchor circle)
			)
			(primitives
				(gr_poly
					(pts
						(arc
							(start -0.1778 -0.2794)
							(mid -0.249642 -0.249642)
							(end -0.2794 -0.1778)
						)
						(arc
							(start -0.2794 0.1778)
							(mid -0.249642 0.249642)
							(end -0.1778 0.2794)
						)
						(arc
							(start 0.1778 0.2794)
							(mid 0.249642 0.249642)
							(end 0.2794 0.1778)
						)
						(arc
							(start 0.2794 -0.1778)
							(mid 0.249642 -0.249642)
							(end 0.1778 -0.2794)
						)
					)
					(width 0)
					(fill yes)
				)
			)
		)
		(pad "2" smd custom
			(at 0 0.4445 90)
			(size 0.1397 0.1397)
			(layers "F.Cu" "F.Mask" "F.Paste")
			(net "P5VB_AGND")
			(options
				(clearance outline)
				(anchor circle)
			)
			(primitives
				(gr_poly
					(pts
						(arc
							(start -0.1778 -0.2794)
							(mid -0.249642 -0.249642)
							(end -0.2794 -0.1778)
						)
						(arc
							(start -0.2794 0.1778)
							(mid -0.249642 0.249642)
							(end -0.1778 0.2794)
						)
						(arc
							(start 0.1778 0.2794)
							(mid 0.249642 0.249642)
							(end 0.2794 0.1778)
						)
						(arc
							(start 0.2794 -0.1778)
							(mid 0.249642 -0.249642)
							(end 0.1778 -0.2794)
						)
					)
					(width 0)
					(fill yes)
				)
			)
		)
	)
	(footprint ""
		(layer "F.Cu")
		(at 21.082 -393.7)
		(property "Reference" "R509"
			(at 0 0 0)
			(layer "F.SilkS")
			(hide yes)
			(effects
				(font
					(size 1.27 1.27)
				)
			)
		)
		(property "Value" "0R2J-2-GP"
			(at 0.064008 -3.993896 0)
			(unlocked yes)
			(layer "F.Fab")
			(hide yes)
			(effects
				(font
					(size 1.016 1.016)
					(thickness 0.1524)
				)
			)
		)
		(property "Device Type" "R402H16"
			(at 0.064008 -5.517896 0)
			(unlocked yes)
			(layer "F.Fab")
			(hide yes)
			(effects
				(font
					(size 1.016 1.016)
					(thickness 0.1524)
				)
			)
		)
		(duplicate_pad_numbers_are_jumpers no)
		(fp_line
			(start -0.508 -0.9398)
			(end -0.508 0.9398)
			(stroke
				(width 0.1524)
				(type default)
			)
			(layer "F.SilkS")
		)
		(fp_line
			(start 0.508 -0.9398)
			(end -0.508 -0.9398)
			(stroke
				(width 0.1524)
				(type default)
			)
			(layer "F.SilkS")
		)
		(fp_rect
			(start -0.508 0.9398)
			(end 0.508 -0.9398)
			(stroke
				(width 0)
				(type default)
			)
			(fill no)
			(layer "F.CrtYd")
		)
		(fp_rect
			(start -0.508 0.9398)
			(end 0.508 -0.9398)
			(stroke
				(width 0)
				(type default)
			)
			(fill no)
			(layer "F.Fab")
		)
		(pad "1" smd custom
			(at 0 -0.4445)
			(size 0.1397 0.1397)
			(layers "F.Cu" "F.Mask" "F.Paste")
			(net "I2C_D_SDA_DAMP_A")
			(options
				(clearance outline)
				(anchor circle)
			)
			(primitives
				(gr_poly
					(pts
						(arc
							(start -0.1778 -0.2794)
							(mid -0.249642 -0.249642)
							(end -0.2794 -0.1778)
						)
						(arc
							(start -0.2794 0.1778)
							(mid -0.249642 0.249642)
							(end -0.1778 0.2794)
						)
						(arc
							(start 0.1778 0.2794)
							(mid 0.249642 0.249642)
							(end 0.2794 0.1778)
						)
						(arc
							(start 0.2794 -0.1778)
							(mid 0.249642 -0.249642)
							(end 0.1778 -0.2794)
						)
					)
					(width 0)
					(fill yes)
				)
			)
		)
		(pad "2" smd custom
			(at 0 0.4445)
			(size 0.1397 0.1397)
			(layers "F.Cu" "F.Mask" "F.Paste")
			(net "I2C_D_SDA")
			(options
				(clearance outline)
				(anchor circle)
			)
			(primitives
				(gr_poly
					(pts
						(arc
							(start -0.1778 -0.2794)
							(mid -0.249642 -0.249642)
							(end -0.2794 -0.1778)
						)
						(arc
							(start -0.2794 0.1778)
							(mid -0.249642 0.249642)
							(end -0.1778 0.2794)
						)
						(arc
							(start 0.1778 0.2794)
							(mid 0.249642 0.249642)
							(end 0.2794 0.1778)
						)
						(arc
							(start 0.2794 -0.1778)
							(mid 0.249642 -0.249642)
							(end 0.1778 -0.2794)
						)
					)
					(width 0)
					(fill yes)
				)
			)
		)
	)
)
